# S9S_MB_2U (Grand Teton) — schematic netlist excerpt (pin names and nets, part order shuffled) for the footprints in the layout excerpt that follows; sources: Cadence DE-HDL packaged netlist, KiCad conversion of 03242023_DA0F0TMBIJ0_F0T_Motherboard_J_brd_V01_OCP.brd

R420  Q_RES  1K 1% CHIP  pkg 0402LF  page 153 : A = SGPIO_OCP_SFF_LD_N ; B = P3V3_OCP_SFF
R567  Q_RES  4.7K 1% EMPTY  pkg 0402LF  page 206 : A = P3V3 ; B = PD_DB2000_SMB_SA1
C43  Q_CAP  10UF 16V 10% X6S  pkg C0805  page 95 : A = P12V_S3_AUX_CPU0_NVDIMM ; B = GND

(kicad_pcb
	(version 20260206)
	(generator "pcbnew")
	(generator_version "10.0")
	(general
		(thickness 1.6)
		(legacy_teardrops no)
	)
	(paper "A4")
	(title_block
		(title "03242023_DA0F0TMBIJ0_F0T_Motherboard_J_brd_V01_OCP.brd")
		(comment 1 "Grand Teton / footprints 4574-4576 of 6105")
	)
	(layers
		(0 "F.Cu" signal "TOP")
		(4 "In1.Cu" signal "GND")
		(6 "In2.Cu" signal "IN1")
		(8 "In3.Cu" signal "GND1")
		(10 "In4.Cu" signal "IN2")
		(12 "In5.Cu" signal "GND2")
		(14 "In6.Cu" signal "IN3")
		(16 "In7.Cu" signal "GND3")
		(18 "In8.Cu" signal "VCC")
		(20 "In9.Cu" signal "VCC1")
		(22 "In10.Cu" signal "GND4")
		(24 "In11.Cu" signal "IN4")
		(26 "In12.Cu" signal "GND5")
		(28 "In13.Cu" signal "IN5")
		(30 "In14.Cu" signal "GND6")
		(32 "In15.Cu" signal "IN6")
		(34 "In16.Cu" signal "GND7")
		(2 "B.Cu" signal "BOTTOM")
		(9 "F.Adhes" user "F.Adhesive")
		(11 "B.Adhes" user "B.Adhesive")
		(13 "F.Paste" user "Package Geometry/Pastemask Top")
		(15 "B.Paste" user "Package Geometry/Pastemask Bottom")
		(5 "F.SilkS" user "Ref Des/Silkscreen Top")
		(7 "B.SilkS" user "Ref Des/Silkscreen Bottom")
		(1 "F.Mask" user "Board Geometry/Soldermask Top")
		(3 "B.Mask" user "Board Geometry/Soldermask Bottom")
		(17 "Dwgs.User" user "User.Drawings")
		(19 "Cmts.User" user "User.Comments")
		(21 "Eco1.User" user "User.Eco1")
		(23 "Eco2.User" user "User.Eco2")
		(25 "Edge.Cuts" user "Board Geometry/Outline")
		(27 "Margin" user)
		(31 "F.CrtYd" user "Package Geometry/Place Bound Top")
		(29 "B.CrtYd" user "Package Geometry/Place Bound Bottom")
		(35 "F.Fab" user "Ref Des/Assembly Top")
		(33 "B.Fab" user "Ref Des/Assembly Bottom")
	)
	(footprint ""
		(layer "B.Cu")
		(at 244.944138 -128.343914 90)
		(property "Reference" "R567"
			(at 0 0 90)
			(layer "B.SilkS")
			(hide yes)
			(effects
				(font
					(size 1.27 1.27)
				)
				(justify mirror)
			)
		)
		(property "Value" ""
			(at 0 0 90)
			(layer "B.Fab")
			(effects
				(font
					(size 1.27 1.27)
				)
				(justify mirror)
			)
		)
		(duplicate_pad_numbers_are_jumpers no)
		(fp_line
			(start 0.7874 -0.4064)
			(end -0.7874 -0.4064)
			(stroke
				(width 0.1524)
				(type default)
			)
			(layer "B.SilkS")
		)
		(fp_line
			(start -0.7874 -0.4064)
			(end -0.7874 0.4064)
			(stroke
				(width 0.1524)
				(type default)
			)
			(layer "B.SilkS")
		)
		(fp_line
			(start 0.7874 0.4064)
			(end 0.7874 -0.4064)
			(stroke
				(width 0.1524)
				(type default)
			)
			(layer "B.SilkS")
		)
		(fp_line
			(start -0.7874 0.4064)
			(end 0.7874 0.4064)
			(stroke
				(width 0.1524)
				(type default)
			)
			(layer "B.SilkS")
		)
		(fp_line
			(start 0.67945 -0.305054)
			(end 0.12065 -0.305054)
			(stroke
				(width 0.1)
				(type default)
			)
			(layer "B.Fab")
		)
		(fp_line
			(start 0.12065 -0.305054)
			(end 0.12065 -0.2794)
			(stroke
				(width 0.1)
				(type default)
			)
			(layer "B.Fab")
		)
		(fp_line
			(start -0.12065 -0.3048)
			(end -0.67945 -0.3048)
			(stroke
				(width 0.1)
				(type default)
			)
			(layer "B.Fab")
		)
		(fp_line
			(start -0.67945 -0.3048)
			(end -0.67945 0.3048)
			(stroke
				(width 0.1)
				(type default)
			)
			(layer "B.Fab")
		)
		(fp_line
			(start 0.12065 -0.2794)
			(end -0.12065 -0.2794)
			(stroke
				(width 0.1)
				(type default)
			)
			(layer "B.Fab")
		)
		(fp_line
			(start -0.12065 -0.2794)
			(end -0.12065 -0.3048)
			(stroke
				(width 0.1)
				(type default)
			)
			(layer "B.Fab")
		)
		(fp_line
			(start 0.12065 0.2794)
			(end 0.12065 0.3048)
			(stroke
				(width 0.1)
				(type default)
			)
			(layer "B.Fab")
		)
		(fp_line
			(start -0.120396 0.2794)
			(end 0.12065 0.2794)
			(stroke
				(width 0.1)
				(type default)
			)
			(layer "B.Fab")
		)
		(fp_line
			(start 0.67945 0.3048)
			(end 0.67945 -0.305054)
			(stroke
				(width 0.1)
				(type default)
			)
			(layer "B.Fab")
		)
		(fp_line
			(start 0.12065 0.3048)
			(end 0.67945 0.3048)
			(stroke
				(width 0.1)
				(type default)
			)
			(layer "B.Fab")
		)
		(fp_line
			(start -0.120396 0.3048)
			(end -0.120396 0.2794)
			(stroke
				(width 0.1)
				(type default)
			)
			(layer "B.Fab")
		)
		(fp_line
			(start -0.67945 0.3048)
			(end -0.120396 0.3048)
			(stroke
				(width 0.1)
				(type default)
			)
			(layer "B.Fab")
		)
		(pad "1" smd circle
			(at 0.40005 0 270)
			(size 0 0)
			(layers "B.Cu" "B.Mask" "B.Paste")
			(net "P3V3")
		)
		(pad "2" smd circle
			(at -0.40005 0 270)
			(size 0 0)
			(layers "B.Cu" "B.Mask" "B.Paste")
			(net "PD_DB2000_SMB_SA1")
		)
	)
	(footprint ""
		(layer "B.Cu")
		(at 452.62546 -10.60577 90)
		(property "Reference" "R420"
			(at 0 0 90)
			(layer "B.SilkS")
			(hide yes)
			(effects
				(font
					(size 1.27 1.27)
				)
				(justify mirror)
			)
		)
		(property "Value" ""
			(at 0 0 90)
			(layer "B.Fab")
			(effects
				(font
					(size 1.27 1.27)
				)
				(justify mirror)
			)
		)
		(duplicate_pad_numbers_are_jumpers no)
		(fp_line
			(start 0.7874 -0.4064)
			(end -0.7874 -0.4064)
			(stroke
				(width 0.1524)
				(type default)
			)
			(layer "B.SilkS")
		)
		(fp_line
			(start -0.7874 -0.4064)
			(end -0.7874 0.4064)
			(stroke
				(width 0.1524)
				(type default)
			)
			(layer "B.SilkS")
		)
		(fp_line
			(start 0.7874 0.4064)
			(end 0.7874 -0.4064)
			(stroke
				(width 0.1524)
				(type default)
			)
			(layer "B.SilkS")
		)
		(fp_line
			(start -0.7874 0.4064)
			(end 0.7874 0.4064)
			(stroke
				(width 0.1524)
				(type default)
			)
			(layer "B.SilkS")
		)
		(fp_line
			(start 0.67945 -0.305054)
			(end 0.12065 -0.305054)
			(stroke
				(width 0.1)
				(type default)
			)
			(layer "B.Fab")
		)
		(fp_line
			(start 0.12065 -0.305054)
			(end 0.12065 -0.2794)
			(stroke
				(width 0.1)
				(type default)
			)
			(layer "B.Fab")
		)
		(fp_line
			(start -0.12065 -0.3048)
			(end -0.67945 -0.3048)
			(stroke
				(width 0.1)
				(type default)
			)
			(layer "B.Fab")
		)
		(fp_line
			(start -0.67945 -0.3048)
			(end -0.67945 0.3048)
			(stroke
				(width 0.1)
				(type default)
			)
			(layer "B.Fab")
		)
		(fp_line
			(start 0.12065 -0.2794)
			(end -0.12065 -0.2794)
			(stroke
				(width 0.1)
				(type default)
			)
			(layer "B.Fab")
		)
		(fp_line
			(start -0.12065 -0.2794)
			(end -0.12065 -0.3048)
			(stroke
				(width 0.1)
				(type default)
			)
			(layer "B.Fab")
		)
		(fp_line
			(start 0.12065 0.2794)
			(end 0.12065 0.3048)
			(stroke
				(width 0.1)
				(type default)
			)
			(layer "B.Fab")
		)
		(fp_line
			(start -0.120396 0.2794)
			(end 0.12065 0.2794)
			(stroke
				(width 0.1)
				(type default)
			)
			(layer "B.Fab")
		)
		(fp_line
			(start 0.67945 0.3048)
			(end 0.67945 -0.305054)
			(stroke
				(width 0.1)
				(type default)
			)
			(layer "B.Fab")
		)
		(fp_line
			(start 0.12065 0.3048)
			(end 0.67945 0.3048)
			(stroke
				(width 0.1)
				(type default)
			)
			(layer "B.Fab")
		)
		(fp_line
			(start -0.120396 0.3048)
			(end -0.120396 0.2794)
			(stroke
				(width 0.1)
				(type default)
			)
			(layer "B.Fab")
		)
		(fp_line
			(start -0.67945 0.3048)
			(end -0.120396 0.3048)
			(stroke
				(width 0.1)
				(type default)
			)
			(layer "B.Fab")
		)
		(pad "1" smd circle
			(at 0.40005 0 270)
			(size 0 0)
			(layers "B.Cu" "B.Mask" "B.Paste")
			(net "SGPIO_OCP_SFF_LD_N")
		)
		(pad "2" smd circle
			(at -0.40005 0 270)
			(size 0 0)
			(layers "B.Cu" "B.Mask" "B.Paste")
			(net "P3V3_OCP_SFF")
		)
	)
	(footprint ""
		(layer "B.Cu")
		(at 441.005214 -321.549776 -90)
		(property "Reference" "C43"
			(at 0 0 90)
			(layer "B.SilkS")
			(hide yes)
			(effects
				(font
					(size 1.27 1.27)
				)
				(justify mirror)
			)
		)
		(property "Value" ""
			(at 0 0 90)
			(layer "B.Fab")
			(effects
				(font
					(size 1.27 1.27)
				)
				(justify mirror)
			)
		)
		(duplicate_pad_numbers_are_jumpers no)
		(fp_line
			(start -1.524 0.762)
			(end 1.524 0.762)
			(stroke
				(width 0.1524)
				(type default)
			)
			(layer "B.SilkS")
		)
		(fp_line
			(start 1.524 0.762)
			(end 1.524 -0.762)
			(stroke
				(width 0.1524)
				(type default)
			)
			(layer "B.SilkS")
		)
		(fp_line
			(start -1.524 -0.762)
			(end -1.524 0.762)
			(stroke
				(width 0.1524)
				(type default)
			)
			(layer "B.SilkS")
		)
		(fp_line
			(start 1.524 -0.762)
			(end -1.524 -0.762)
			(stroke
				(width 0.1524)
				(type default)
			)
			(layer "B.SilkS")
		)
		(fp_line
			(start -1.1049 0.724916)
			(end -1.1049 -0.724916)
			(stroke
				(width 0.1)
				(type default)
			)
			(layer "B.Fab")
		)
		(fp_line
			(start 1.1049 0.724916)
			(end -1.1049 0.724916)
			(stroke
				(width 0.1)
				(type default)
			)
			(layer "B.Fab")
		)
		(fp_line
			(start -1.1049 -0.724916)
			(end 1.1049 -0.724916)
			(stroke
				(width 0.1)
				(type default)
			)
			(layer "B.Fab")
		)
		(fp_line
			(start 1.1049 -0.724916)
			(end 1.1049 0.724916)
			(stroke
				(width 0.1)
				(type default)
			)
			(layer "B.Fab")
		)
		(pad "1" smd rect
			(at 0.889 0 270)
			(size 1.016 1.27)
			(layers "B.Cu" "B.Mask" "B.Paste")
			(net "P12V_S3_AUX_CPU0_NVDIMM")
		)
		(pad "2" smd rect
			(at -0.889 0 270)
			(size 1.016 1.27)
			(layers "B.Cu" "B.Mask" "B.Paste")
			(net "GND")
		)
	)
)
